(kicad_pcb
	(version 20260206)
	(generator "pcbnew")
	(generator_version "10.0")
	(general
		(thickness 1.6)
		(legacy_teardrops no)
	)
	(paper "A4")
	(title_block
		(title "01162023_DA0F0TEBIF0_F0T_Expander_BD_F_brd_V02_OCP.brd")
		(comment 1 "Grand Teton / footprint 5622 of 9728 (PEX2), pads 2359-2397 of 2397")
	)
	(layers
		(0 "F.Cu" signal "TOP")
		(4 "In1.Cu" signal "GND")
		(6 "In2.Cu" signal "VCC")
		(8 "In3.Cu" signal "VCC1")
		(10 "In4.Cu" signal "GND1")
		(12 "In5.Cu" signal "IN1")
		(14 "In6.Cu" signal "GND2")
		(16 "In7.Cu" signal "IN2")
		(18 "In8.Cu" signal "GND3")
		(20 "In9.Cu" signal "IN3")
		(22 "In10.Cu" signal "GND4")
		(24 "In11.Cu" signal "IN4")
		(26 "In12.Cu" signal "GND5")
		(28 "In13.Cu" signal "IN5")
		(30 "In14.Cu" signal "GND6")
		(32 "In15.Cu" signal "IN6")
		(34 "In16.Cu" signal "GND7")
		(2 "B.Cu" signal "BOTTOM")
		(9 "F.Adhes" user "F.Adhesive")
		(11 "B.Adhes" user "B.Adhesive")
		(13 "F.Paste" user "Package Geometry/Pastemask Top")
		(15 "B.Paste" user "Package Geometry/Pastemask Bottom")
		(5 "F.SilkS" user "Ref Des/Silkscreen Top")
		(7 "B.SilkS" user "Ref Des/Silkscreen Bottom")
		(1 "F.Mask" user "Board Geometry/Soldermask Top")
		(3 "B.Mask" user "Board Geometry/Soldermask Bottom")
		(17 "Dwgs.User" user "User.Drawings")
		(19 "Cmts.User" user "User.Comments")
		(21 "Eco1.User" user "User.Eco1")
		(23 "Eco2.User" user "User.Eco2")
		(25 "Edge.Cuts" user "Board Geometry/Outline")
		(27 "Margin" user)
		(31 "F.CrtYd" user "Package Geometry/Place Bound Top")
		(29 "B.CrtYd" user "Package Geometry/Place Bound Bottom")
		(35 "F.Fab" user "Ref Des/Assembly Top")
		(33 "B.Fab" user "Ref Des/Assembly Bottom")
	)
	(footprint ""
		(layer "F.Cu")
		(at 291.84981 -295.89984)
		(property "Reference" "PEX2"
			(at -3.35153 35.56762 0)
			(unlocked yes)
			(layer "F.SilkS")
			(effects
				(font
					(size 2.032 1.524)
					(thickness 0.1524)
				)
				(justify left)
			)
		)
		(property "Value" ""
			(at 0 0 0)
			(layer "F.Fab")
			(effects
				(font
					(size 1.27 1.27)
				)
			)
		)
		(duplicate_pad_numbers_are_jumpers no)
		(pad "Y11" smd circle
			(at -13.299948 -4.750054)
			(size 0.4572 0.4572)
			(layers "F.Cu" "F.Mask" "F.Paste")
			(net "GND")
		)
		(pad "Y12" smd circle
			(at -12.349988 -4.750054)
			(size 0.4572 0.4572)
			(layers "F.Cu" "F.Mask" "F.Paste")
			(net "P1V8_PEX")
		)
		(pad "Y13" smd circle
			(at -11.400028 -4.750054)
			(size 0.4572 0.4572)
			(layers "F.Cu" "F.Mask" "F.Paste")
			(net "GND")
		)
		(pad "Y14" smd circle
			(at -10.450068 -4.750054)
			(size 0.4572 0.4572)
			(layers "F.Cu" "F.Mask" "F.Paste")
			(net "P0V8_PEX2")
		)
		(pad "Y15" smd circle
			(at -9.500108 -4.750054)
			(size 0.4572 0.4572)
			(layers "F.Cu" "F.Mask" "F.Paste")
			(net "GND")
		)
		(pad "Y16" smd circle
			(at -8.549894 -4.750054)
			(size 0.4572 0.4572)
			(layers "F.Cu" "F.Mask" "F.Paste")
			(net "P0V8_SERDES_VDDA_PEX2")
		)
		(pad "Y17" smd circle
			(at -7.599934 -4.750054)
			(size 0.4572 0.4572)
			(layers "F.Cu" "F.Mask" "F.Paste")
			(net "P0V8_SERDES_VDDA_PEX2")
		)
		(pad "Y18" smd circle
			(at -6.649974 -4.750054)
			(size 0.4572 0.4572)
			(layers "F.Cu" "F.Mask" "F.Paste")
			(net "P0V8_SERDES_VDDA_PEX2")
		)
		(pad "Y19" smd circle
			(at -5.700014 -4.750054)
			(size 0.4572 0.4572)
			(layers "F.Cu" "F.Mask" "F.Paste")
			(net "P0V8_SERDES_VDDA_PEX2")
		)
		(pad "Y20" smd circle
			(at -4.750054 -4.750054)
			(size 0.4572 0.4572)
			(layers "F.Cu" "F.Mask" "F.Paste")
			(net "P0V8_SERDES_VDDA_PEX2")
		)
		(pad "Y21" smd circle
			(at -3.800094 -4.750054)
			(size 0.4572 0.4572)
			(layers "F.Cu" "F.Mask" "F.Paste")
			(net "P0V8_SERDES_VDDA_PEX2")
		)
		(pad "Y22" smd circle
			(at -2.84988 -4.750054)
			(size 0.4572 0.4572)
			(layers "F.Cu" "F.Mask" "F.Paste")
			(net "P0V8_SERDES_VDDA_PEX2")
		)
		(pad "Y23" smd circle
			(at -1.89992 -4.750054)
			(size 0.4572 0.4572)
			(layers "F.Cu" "F.Mask" "F.Paste")
			(net "P0V8_SERDES_VDDA_PEX2")
		)
		(pad "Y24" smd circle
			(at -0.94996 -4.750054)
			(size 0.4572 0.4572)
			(layers "F.Cu" "F.Mask" "F.Paste")
			(net "P0V8_SERDES_VDDA_PEX2")
		)
		(pad "Y25" smd circle
			(at 0 -4.750054)
			(size 0.4572 0.4572)
			(layers "F.Cu" "F.Mask" "F.Paste")
			(net "P0V8_SERDES_VDDA_PEX2")
		)
		(pad "Y26" smd circle
			(at 0.94996 -4.750054)
			(size 0.4572 0.4572)
			(layers "F.Cu" "F.Mask" "F.Paste")
			(net "P0V8_SERDES_VDDA_PEX2")
		)
		(pad "Y27" smd circle
			(at 1.89992 -4.750054)
			(size 0.4572 0.4572)
			(layers "F.Cu" "F.Mask" "F.Paste")
			(net "P0V8_SERDES_VDDA_PEX2")
		)
		(pad "Y28" smd circle
			(at 2.84988 -4.750054)
			(size 0.4572 0.4572)
			(layers "F.Cu" "F.Mask" "F.Paste")
			(net "P0V8_SERDES_VDDA_PEX2")
		)
		(pad "Y29" smd circle
			(at 3.800094 -4.750054)
			(size 0.4572 0.4572)
			(layers "F.Cu" "F.Mask" "F.Paste")
			(net "P0V8_SERDES_VDDA_PEX2")
		)
		(pad "Y30" smd circle
			(at 4.750054 -4.750054)
			(size 0.4572 0.4572)
			(layers "F.Cu" "F.Mask" "F.Paste")
			(net "P0V8_SERDES_VDDA_PEX2")
		)
		(pad "Y31" smd circle
			(at 5.700014 -4.750054)
			(size 0.4572 0.4572)
			(layers "F.Cu" "F.Mask" "F.Paste")
			(net "P0V8_SERDES_VDDA_PEX2")
		)
		(pad "Y32" smd circle
			(at 6.649974 -4.750054)
			(size 0.4572 0.4572)
			(layers "F.Cu" "F.Mask" "F.Paste")
			(net "P0V8_SERDES_VDDA_PEX2")
		)
		(pad "Y33" smd circle
			(at 7.599934 -4.750054)
			(size 0.4572 0.4572)
			(layers "F.Cu" "F.Mask" "F.Paste")
			(net "P0V8_SERDES_VDDA_PEX2")
		)
		(pad "Y34" smd circle
			(at 8.549894 -4.750054)
			(size 0.4572 0.4572)
			(layers "F.Cu" "F.Mask" "F.Paste")
			(net "GND")
		)
		(pad "Y35" smd circle
			(at 9.500108 -4.750054)
			(size 0.4572 0.4572)
			(layers "F.Cu" "F.Mask" "F.Paste")
			(net "P1V8_PEX")
		)
		(pad "Y36" smd circle
			(at 10.450068 -4.750054)
			(size 0.4572 0.4572)
			(layers "F.Cu" "F.Mask" "F.Paste")
			(net "GND")
		)
		(pad "Y37" smd circle
			(at 11.400028 -4.750054)
			(size 0.4572 0.4572)
			(layers "F.Cu" "F.Mask" "F.Paste")
			(net "GND")
		)
		(pad "Y38" smd circle
			(at 12.349988 -4.750054)
			(size 0.4572 0.4572)
			(layers "F.Cu" "F.Mask" "F.Paste")
			(net "GND")
		)
		(pad "Y39" smd circle
			(at 13.299948 -4.750054)
			(size 0.4572 0.4572)
			(layers "F.Cu" "F.Mask" "F.Paste")
			(net "PEX2_ADCTEMP_VINP0")
		)
		(pad "Y40" smd circle
			(at 14.249908 -4.750054)
			(size 0.4572 0.4572)
			(layers "F.Cu" "F.Mask" "F.Paste")
			(net "GND")
		)
		(pad "Y41" smd circle
			(at 15.200122 -4.750054)
			(size 0.4572 0.4572)
			(layers "F.Cu" "F.Mask" "F.Paste")
			(net "Net_1665")
		)
		(pad "Y42" smd circle
			(at 16.150082 -4.750054)
			(size 0.4572 0.4572)
			(layers "F.Cu" "F.Mask" "F.Paste")
			(net "Net_1685")
		)
		(pad "Y43" smd circle
			(at 17.100042 -4.750054)
			(size 0.4572 0.4572)
			(layers "F.Cu" "F.Mask" "F.Paste")
			(net "GND")
		)
		(pad "Y44" smd circle
			(at 18.050002 -4.750054)
			(size 0.4572 0.4572)
			(layers "F.Cu" "F.Mask" "F.Paste")
			(net "GND")
		)
		(pad "Y45" smd circle
			(at 18.999962 -4.750054)
			(size 0.4572 0.4572)
			(layers "F.Cu" "F.Mask" "F.Paste")
			(net "GND")
		)
		(pad "Y46" smd circle
			(at 19.949922 -4.750054)
			(size 0.4572 0.4572)
			(layers "F.Cu" "F.Mask" "F.Paste")
			(net "GND")
		)
		(pad "Y47" smd circle
			(at 20.899882 -4.750054)
			(size 0.4572 0.4572)
			(layers "F.Cu" "F.Mask" "F.Paste")
			(net "GND")
		)
		(pad "Y48" smd circle
			(at 21.850096 -4.750054)
			(size 0.4572 0.4572)
			(layers "F.Cu" "F.Mask" "F.Paste")
			(net "Net_1597")
		)
		(pad "Y49" smd circle
			(at 22.800056 -4.750054)
			(size 0.4572 0.4572)
			(layers "F.Cu" "F.Mask" "F.Paste")
			(net "Net_1604")
		)
	)
)
